(kicad_pcb
	(version 20260206)
	(generator "pcbnew")
	(generator_version "10.0")
	(general
		(thickness 1.6)
		(legacy_teardrops no)
	)
	(paper "A4")
	(title_block
		(title "Bryce Canyon_IOM_IOC_16318-2_OCP.brd")
		(comment 1 "Bryce Canyon / footprints 1048-1055 of 1605")
	)
	(layers
		(0 "F.Cu" signal "TOP")
		(4 "In1.Cu" signal "L2GND")
		(6 "In2.Cu" signal "L3")
		(8 "In3.Cu" signal "L4VCC")
		(10 "In4.Cu" signal "L5VCC")
		(12 "In5.Cu" signal "L6")
		(14 "In6.Cu" signal "L7GND")
		(2 "B.Cu" signal "BOTTOM")
		(9 "F.Adhes" user "F.Adhesive")
		(11 "B.Adhes" user "B.Adhesive")
		(13 "F.Paste" user "Package Geometry/Pastemask Top")
		(15 "B.Paste" user "Package Geometry/Pastemask Bottom")
		(5 "F.SilkS" user "Ref Des/Silkscreen Top")
		(7 "B.SilkS" user "Ref Des/Silkscreen Bottom")
		(1 "F.Mask" user "Board Geometry/Soldermask Top")
		(3 "B.Mask" user "Board Geometry/Soldermask Bottom")
		(17 "Dwgs.User" user "User.Drawings")
		(19 "Cmts.User" user "User.Comments")
		(21 "Eco1.User" user "User.Eco1")
		(23 "Eco2.User" user "User.Eco2")
		(25 "Edge.Cuts" user "Board Geometry/Outline")
		(27 "Margin" user)
		(31 "F.CrtYd" user "Package Geometry/Place Bound Top")
		(29 "B.CrtYd" user "Package Geometry/Place Bound Bottom")
		(35 "F.Fab" user "Ref Des/Assembly Top")
		(33 "B.Fab" user "Ref Des/Assembly Bottom")
	)
	(footprint ""
		(layer "B.Cu")
		(at 191.689736 -25.273 -90)
		(property "Reference" "C491"
			(at 0 0 90)
			(layer "B.SilkS")
			(hide yes)
			(effects
				(font
					(size 1.27 1.27)
				)
				(justify mirror)
			)
		)
		(property "Value" "SCD01U16V1KX-GP"
			(at 2.8321 -1.7399 270)
			(unlocked yes)
			(layer "B.Fab")
			(hide yes)
			(effects
				(font
					(size 1.016 1.016)
					(thickness 0.1524)
				)
				(justify mirror)
			)
		)
		(property "Device Type" "C0201H13"
			(at 2.8321 -3.2639 270)
			(unlocked yes)
			(layer "B.Fab")
			(hide yes)
			(effects
				(font
					(size 1.016 1.016)
					(thickness 0.1524)
				)
				(justify mirror)
			)
		)
		(duplicate_pad_numbers_are_jumpers no)
		(fp_rect
			(start 0.2794 0.6477)
			(end -0.2794 -0.6477)
			(stroke
				(width 0)
				(type default)
			)
			(fill no)
			(layer "B.CrtYd")
		)
		(fp_rect
			(start 0.2794 0.6477)
			(end -0.2794 -0.6477)
			(stroke
				(width 0)
				(type default)
			)
			(fill no)
			(layer "B.Fab")
		)
		(pad "1" smd custom
			(at 0 -0.2794 90)
			(size 0.0762 0.0762)
			(layers "B.Cu" "B.Mask" "B.Paste")
			(net "PHY_CON_A_TO_IOC_3_DN")
			(options
				(clearance outline)
				(anchor circle)
			)
			(primitives
				(gr_poly
					(pts
						(arc
							(start 0.1524 0.127)
							(mid 0.137521 0.162921)
							(end 0.1016 0.1778)
						)
						(arc
							(start -0.1016 0.1778)
							(mid -0.137521 0.162921)
							(end -0.1524 0.127)
						)
						(arc
							(start -0.1524 -0.127)
							(mid -0.137521 -0.162921)
							(end -0.1016 -0.1778)
						)
						(arc
							(start 0.1016 -0.1778)
							(mid 0.137521 -0.162921)
							(end 0.1524 -0.127)
						)
					)
					(width 0)
					(fill yes)
				)
			)
		)
		(pad "2" smd custom
			(at 0 0.2794 90)
			(size 0.0762 0.0762)
			(layers "B.Cu" "B.Mask" "B.Paste")
			(net "PHY_CON_A_TO_IOC_3_DN_C")
			(options
				(clearance outline)
				(anchor circle)
			)
			(primitives
				(gr_poly
					(pts
						(arc
							(start 0.1524 0.127)
							(mid 0.137521 0.162921)
							(end 0.1016 0.1778)
						)
						(arc
							(start -0.1016 0.1778)
							(mid -0.137521 0.162921)
							(end -0.1524 0.127)
						)
						(arc
							(start -0.1524 -0.127)
							(mid -0.137521 -0.162921)
							(end -0.1016 -0.1778)
						)
						(arc
							(start 0.1016 -0.1778)
							(mid 0.137521 -0.162921)
							(end 0.1524 -0.127)
						)
					)
					(width 0)
					(fill yes)
				)
			)
		)
	)
	(footprint ""
		(layer "B.Cu")
		(at 179.452524 -152.475946 180)
		(property "Reference" "R466"
			(at 0 0 0)
			(layer "B.SilkS")
			(hide yes)
			(effects
				(font
					(size 1.27 1.27)
				)
				(justify mirror)
			)
		)
		(property "Value" "2D7R3-GP"
			(at 0.0254 -2.5146 180)
			(unlocked yes)
			(layer "B.Fab")
			(hide yes)
			(effects
				(font
					(size 1.016 1.016)
					(thickness 0.1524)
				)
				(justify mirror)
			)
		)
		(property "Device Type" "R603H22"
			(at 0.0254 -4.0386 180)
			(unlocked yes)
			(layer "B.Fab")
			(hide yes)
			(effects
				(font
					(size 1.016 1.016)
					(thickness 0.1524)
				)
				(justify mirror)
			)
		)
		(duplicate_pad_numbers_are_jumpers no)
		(fp_line
			(start 0.4826 0)
			(end 0.2032 0)
			(stroke
				(width 0.2032)
				(type default)
			)
			(layer "B.SilkS")
		)
		(fp_line
			(start -0.2032 0)
			(end -0.4826 0)
			(stroke
				(width 0.2032)
				(type default)
			)
			(layer "B.SilkS")
		)
		(fp_rect
			(start 0.5842 1.3335)
			(end -0.5842 -1.3335)
			(stroke
				(width 0)
				(type default)
			)
			(fill no)
			(layer "B.CrtYd")
		)
		(fp_rect
			(start 0.5842 1.3335)
			(end -0.5842 -1.3335)
			(stroke
				(width 0)
				(type default)
			)
			(fill no)
			(layer "B.Fab")
		)
		(pad "1" smd custom
			(at 0 -0.762)
			(size 0.2159 0.2159)
			(layers "B.Cu" "B.Mask" "B.Paste")
			(net "P5V_VBST")
			(options
				(clearance outline)
				(anchor circle)
			)
			(primitives
				(gr_poly
					(pts
						(arc
							(start -0.3302 0.4318)
							(mid -0.402042 0.402042)
							(end -0.4318 0.3302)
						)
						(arc
							(start -0.4318 -0.3302)
							(mid -0.402042 -0.402042)
							(end -0.3302 -0.4318)
						)
						(arc
							(start 0.3302 -0.4318)
							(mid 0.402042 -0.402042)
							(end 0.4318 -0.3302)
						)
						(arc
							(start 0.4318 0.3302)
							(mid 0.402042 0.402042)
							(end 0.3302 0.4318)
						)
					)
					(width 0)
					(fill yes)
				)
			)
		)
		(pad "2" smd custom
			(at 0 0.762)
			(size 0.2159 0.2159)
			(layers "B.Cu" "B.Mask" "B.Paste")
			(net "P5V_VBST_RC")
			(options
				(clearance outline)
				(anchor circle)
			)
			(primitives
				(gr_poly
					(pts
						(arc
							(start -0.3302 0.4318)
							(mid -0.402042 0.402042)
							(end -0.4318 0.3302)
						)
						(arc
							(start -0.4318 -0.3302)
							(mid -0.402042 -0.402042)
							(end -0.3302 -0.4318)
						)
						(arc
							(start 0.3302 -0.4318)
							(mid 0.402042 -0.402042)
							(end 0.4318 -0.3302)
						)
						(arc
							(start 0.4318 0.3302)
							(mid 0.402042 0.402042)
							(end 0.3302 0.4318)
						)
					)
					(width 0)
					(fill yes)
				)
			)
		)
	)
	(footprint ""
		(layer "B.Cu")
		(at 141.986 -16.4338 -90)
		(property "Reference" "C521"
			(at 0 0 90)
			(layer "B.SilkS")
			(hide yes)
			(effects
				(font
					(size 1.27 1.27)
				)
				(justify mirror)
			)
		)
		(property "Value" "SCD1U16V2KX-3GP"
			(at -1.1811 -2.7051 270)
			(unlocked yes)
			(layer "B.Fab")
			(hide yes)
			(effects
				(font
					(size 1.016 1.016)
					(thickness 0.1524)
				)
				(justify mirror)
			)
		)
		(property "Device Type" "C402H22"
			(at -1.1811 -4.2291 270)
			(unlocked yes)
			(layer "B.Fab")
			(hide yes)
			(effects
				(font
					(size 1.016 1.016)
					(thickness 0.1524)
				)
				(justify mirror)
			)
		)
		(duplicate_pad_numbers_are_jumpers no)
		(fp_rect
			(start 0.4318 0.9525)
			(end -0.4318 -0.9525)
			(stroke
				(width 0)
				(type default)
			)
			(fill no)
			(layer "B.CrtYd")
		)
		(fp_rect
			(start 0.4318 0.9525)
			(end -0.4318 -0.9525)
			(stroke
				(width 0)
				(type default)
			)
			(fill no)
			(layer "B.Fab")
		)
		(pad "1" smd custom
			(at 0 -0.4445 90)
			(size 0.1524 0.1524)
			(layers "B.Cu" "B.Mask" "B.Paste")
			(net "P1V8")
			(options
				(clearance outline)
				(anchor circle)
			)
			(primitives
				(gr_poly
					(pts
						(arc
							(start 0.3048 0.2032)
							(mid 0.275042 0.275042)
							(end 0.2032 0.3048)
						)
						(arc
							(start -0.2032 0.3048)
							(mid -0.275042 0.275042)
							(end -0.3048 0.2032)
						)
						(arc
							(start -0.3048 -0.2032)
							(mid -0.275042 -0.275042)
							(end -0.2032 -0.3048)
						)
						(arc
							(start 0.2032 -0.3048)
							(mid 0.275042 -0.275042)
							(end 0.3048 -0.2032)
						)
					)
					(width 0)
					(fill yes)
				)
			)
		)
		(pad "2" smd custom
			(at 0 0.4445 90)
			(size 0.1524 0.1524)
			(layers "B.Cu" "B.Mask" "B.Paste")
			(net "GND")
			(options
				(clearance outline)
				(anchor circle)
			)
			(primitives
				(gr_poly
					(pts
						(arc
							(start 0.3048 0.2032)
							(mid 0.275042 0.275042)
							(end 0.2032 0.3048)
						)
						(arc
							(start -0.2032 0.3048)
							(mid -0.275042 0.275042)
							(end -0.3048 0.2032)
						)
						(arc
							(start -0.3048 -0.2032)
							(mid -0.275042 -0.275042)
							(end -0.2032 -0.3048)
						)
						(arc
							(start 0.2032 -0.3048)
							(mid 0.275042 -0.275042)
							(end 0.3048 -0.2032)
						)
					)
					(width 0)
					(fill yes)
				)
			)
		)
	)
	(footprint ""
		(layer "B.Cu")
		(at 203.9874 -74.0918)
		(property "Reference" "C378"
			(at 0 0 0)
			(layer "B.SilkS")
			(hide yes)
			(effects
				(font
					(size 1.27 1.27)
				)
				(justify mirror)
			)
		)
		(property "Value" "SCD1U6D3V1KX-GP"
			(at 2.8321 -1.7399 0)
			(unlocked yes)
			(layer "B.Fab")
			(hide yes)
			(effects
				(font
					(size 1.016 1.016)
					(thickness 0.1524)
				)
				(justify mirror)
			)
		)
		(property "Device Type" "C0201H13"
			(at 2.8321 -3.2639 0)
			(unlocked yes)
			(layer "B.Fab")
			(hide yes)
			(effects
				(font
					(size 1.016 1.016)
					(thickness 0.1524)
				)
				(justify mirror)
			)
		)
		(duplicate_pad_numbers_are_jumpers no)
		(fp_rect
			(start 0.2794 0.6477)
			(end -0.2794 -0.6477)
			(stroke
				(width 0)
				(type default)
			)
			(fill no)
			(layer "B.CrtYd")
		)
		(fp_rect
			(start 0.2794 0.6477)
			(end -0.2794 -0.6477)
			(stroke
				(width 0)
				(type default)
			)
			(fill no)
			(layer "B.Fab")
		)
		(pad "1" smd custom
			(at 0 -0.2794 180)
			(size 0.0762 0.0762)
			(layers "B.Cu" "B.Mask" "B.Paste")
			(net "SAS0_AVDD")
			(options
				(clearance outline)
				(anchor circle)
			)
			(primitives
				(gr_poly
					(pts
						(arc
							(start 0.1524 0.127)
							(mid 0.137521 0.162921)
							(end 0.1016 0.1778)
						)
						(arc
							(start -0.1016 0.1778)
							(mid -0.137521 0.162921)
							(end -0.1524 0.127)
						)
						(arc
							(start -0.1524 -0.127)
							(mid -0.137521 -0.162921)
							(end -0.1016 -0.1778)
						)
						(arc
							(start 0.1016 -0.1778)
							(mid 0.137521 -0.162921)
							(end 0.1524 -0.127)
						)
					)
					(width 0)
					(fill yes)
				)
			)
		)
		(pad "2" smd custom
			(at 0 0.2794 180)
			(size 0.0762 0.0762)
			(layers "B.Cu" "B.Mask" "B.Paste")
			(net "GND")
			(options
				(clearance outline)
				(anchor circle)
			)
			(primitives
				(gr_poly
					(pts
						(arc
							(start 0.1524 0.127)
							(mid 0.137521 0.162921)
							(end 0.1016 0.1778)
						)
						(arc
							(start -0.1016 0.1778)
							(mid -0.137521 0.162921)
							(end -0.1524 0.127)
						)
						(arc
							(start -0.1524 -0.127)
							(mid -0.137521 -0.162921)
							(end -0.1016 -0.1778)
						)
						(arc
							(start 0.1016 -0.1778)
							(mid 0.137521 -0.162921)
							(end 0.1524 -0.127)
						)
					)
					(width 0)
					(fill yes)
				)
			)
		)
	)
	(footprint ""
		(layer "B.Cu")
		(at 187.9854 -124.405136 180)
		(property "Reference" "R559"
			(at 0 0 0)
			(layer "B.SilkS")
			(hide yes)
			(effects
				(font
					(size 1.27 1.27)
				)
				(justify mirror)
			)
		)
		(property "Value" "10KR2F-2-GP"
			(at -0.064008 -3.993896 180)
			(unlocked yes)
			(layer "B.Fab")
			(hide yes)
			(effects
				(font
					(size 1.016 1.016)
					(thickness 0.1524)
				)
				(justify mirror)
			)
		)
		(property "Device Type" "R402H16"
			(at -0.064008 -5.517896 180)
			(unlocked yes)
			(layer "B.Fab")
			(hide yes)
			(effects
				(font
					(size 1.016 1.016)
					(thickness 0.1524)
				)
				(justify mirror)
			)
		)
		(duplicate_pad_numbers_are_jumpers no)
		(fp_line
			(start 0.508 -0.9398)
			(end 0.508 0.9398)
			(stroke
				(width 0.1524)
				(type default)
			)
			(layer "B.SilkS")
		)
		(fp_line
			(start -0.508 -0.9398)
			(end 0.508 -0.9398)
			(stroke
				(width 0.1524)
				(type default)
			)
			(layer "B.SilkS")
		)
		(fp_rect
			(start 0.508 0.9398)
			(end -0.508 -0.9398)
			(stroke
				(width 0)
				(type default)
			)
			(fill no)
			(layer "B.CrtYd")
		)
		(fp_rect
			(start 0.508 0.9398)
			(end -0.508 -0.9398)
			(stroke
				(width 0)
				(type default)
			)
			(fill no)
			(layer "B.Fab")
		)
		(pad "1" smd custom
			(at 0 -0.4445)
			(size 0.1397 0.1397)
			(layers "B.Cu" "B.Mask" "B.Paste")
			(net "AGND_P0V975")
			(options
				(clearance outline)
				(anchor circle)
			)
			(primitives
				(gr_poly
					(pts
						(arc
							(start -0.1778 0.2794)
							(mid -0.249642 0.249642)
							(end -0.2794 0.1778)
						)
						(arc
							(start -0.2794 -0.1778)
							(mid -0.249642 -0.249642)
							(end -0.1778 -0.2794)
						)
						(arc
							(start 0.1778 -0.2794)
							(mid 0.249642 -0.249642)
							(end 0.2794 -0.1778)
						)
						(arc
							(start 0.2794 0.1778)
							(mid 0.249642 0.249642)
							(end 0.1778 0.2794)
						)
					)
					(width 0)
					(fill yes)
				)
			)
		)
		(pad "2" smd custom
			(at 0 0.4445)
			(size 0.1397 0.1397)
			(layers "B.Cu" "B.Mask" "B.Paste")
			(net "VT235_IMAX")
			(options
				(clearance outline)
				(anchor circle)
			)
			(primitives
				(gr_poly
					(pts
						(arc
							(start -0.1778 0.2794)
							(mid -0.249642 0.249642)
							(end -0.2794 0.1778)
						)
						(arc
							(start -0.2794 -0.1778)
							(mid -0.249642 -0.249642)
							(end -0.1778 -0.2794)
						)
						(arc
							(start 0.1778 -0.2794)
							(mid 0.249642 -0.249642)
							(end 0.2794 -0.1778)
						)
						(arc
							(start 0.2794 0.1778)
							(mid 0.249642 0.249642)
							(end 0.1778 0.2794)
						)
					)
					(width 0)
					(fill yes)
				)
			)
		)
	)
	(footprint ""
		(layer "B.Cu")
		(at 83.102196 -98.454972 180)
		(property "Reference" "R64"
			(at 0 0 0)
			(layer "B.SilkS")
			(hide yes)
			(effects
				(font
					(size 1.27 1.27)
				)
				(justify mirror)
			)
		)
		(property "Value" "10KR2F-2-GP"
			(at -0.064008 -3.993896 180)
			(unlocked yes)
			(layer "B.Fab")
			(hide yes)
			(effects
				(font
					(size 1.016 1.016)
					(thickness 0.1524)
				)
				(justify mirror)
			)
		)
		(property "Device Type" "R402H16"
			(at -0.064008 -5.517896 180)
			(unlocked yes)
			(layer "B.Fab")
			(hide yes)
			(effects
				(font
					(size 1.016 1.016)
					(thickness 0.1524)
				)
				(justify mirror)
			)
		)
		(duplicate_pad_numbers_are_jumpers no)
		(fp_line
			(start 0.508 -0.9398)
			(end 0.508 0.9398)
			(stroke
				(width 0.1524)
				(type default)
			)
			(layer "B.SilkS")
		)
		(fp_line
			(start -0.508 -0.9398)
			(end 0.508 -0.9398)
			(stroke
				(width 0.1524)
				(type default)
			)
			(layer "B.SilkS")
		)
		(fp_rect
			(start 0.508 0.9398)
			(end -0.508 -0.9398)
			(stroke
				(width 0)
				(type default)
			)
			(fill no)
			(layer "B.CrtYd")
		)
		(fp_rect
			(start 0.508 0.9398)
			(end -0.508 -0.9398)
			(stroke
				(width 0)
				(type default)
			)
			(fill no)
			(layer "B.Fab")
		)
		(pad "1" smd custom
			(at 0 -0.4445)
			(size 0.1397 0.1397)
			(layers "B.Cu" "B.Mask" "B.Paste")
			(net "P3V3_STBY")
			(options
				(clearance outline)
				(anchor circle)
			)
			(primitives
				(gr_poly
					(pts
						(arc
							(start -0.1778 0.2794)
							(mid -0.249642 0.249642)
							(end -0.2794 0.1778)
						)
						(arc
							(start -0.2794 -0.1778)
							(mid -0.249642 -0.249642)
							(end -0.1778 -0.2794)
						)
						(arc
							(start 0.1778 -0.2794)
							(mid 0.249642 -0.249642)
							(end 0.2794 -0.1778)
						)
						(arc
							(start 0.2794 0.1778)
							(mid 0.249642 0.249642)
							(end 0.1778 0.2794)
						)
					)
					(width 0)
					(fill yes)
				)
			)
		)
		(pad "2" smd custom
			(at 0 0.4445)
			(size 0.1397 0.1397)
			(layers "B.Cu" "B.Mask" "B.Paste")
			(net "MEZZ_A_PRSNT_120_N")
			(options
				(clearance outline)
				(anchor circle)
			)
			(primitives
				(gr_poly
					(pts
						(arc
							(start -0.1778 0.2794)
							(mid -0.249642 0.249642)
							(end -0.2794 0.1778)
						)
						(arc
							(start -0.2794 -0.1778)
							(mid -0.249642 -0.249642)
							(end -0.1778 -0.2794)
						)
						(arc
							(start 0.1778 -0.2794)
							(mid 0.249642 -0.249642)
							(end 0.2794 -0.1778)
						)
						(arc
							(start 0.2794 0.1778)
							(mid 0.249642 0.249642)
							(end 0.1778 0.2794)
						)
					)
					(width 0)
					(fill yes)
				)
			)
		)
	)
	(footprint ""
		(layer "B.Cu")
		(at 55.25008 -153.68778 90)
		(property "Reference" "C88"
			(at 0 0 90)
			(layer "B.SilkS")
			(hide yes)
			(effects
				(font
					(size 1.27 1.27)
				)
				(justify mirror)
			)
		)
		(property "Value" "SC100P50V2JN-3GP"
			(at -1.1811 -2.7051 90)
			(unlocked yes)
			(layer "B.Fab")
			(hide yes)
			(effects
				(font
					(size 1.016 1.016)
					(thickness 0.1524)
				)
				(justify mirror)
			)
		)
		(property "Device Type" "C402H22"
			(at -1.1811 -4.2291 90)
			(unlocked yes)
			(layer "B.Fab")
			(hide yes)
			(effects
				(font
					(size 1.016 1.016)
					(thickness 0.1524)
				)
				(justify mirror)
			)
		)
		(duplicate_pad_numbers_are_jumpers no)
		(fp_rect
			(start 0.4318 0.9525)
			(end -0.4318 -0.9525)
			(stroke
				(width 0)
				(type default)
			)
			(fill no)
			(layer "B.CrtYd")
		)
		(fp_rect
			(start 0.4318 0.9525)
			(end -0.4318 -0.9525)
			(stroke
				(width 0)
				(type default)
			)
			(fill no)
			(layer "B.Fab")
		)
		(pad "1" smd custom
			(at 0 -0.4445 270)
			(size 0.1524 0.1524)
			(layers "B.Cu" "B.Mask" "B.Paste")
			(net "ADCAV33")
			(options
				(clearance outline)
				(anchor circle)
			)
			(primitives
				(gr_poly
					(pts
						(arc
							(start 0.3048 0.2032)
							(mid 0.275042 0.275042)
							(end 0.2032 0.3048)
						)
						(arc
							(start -0.2032 0.3048)
							(mid -0.275042 0.275042)
							(end -0.3048 0.2032)
						)
						(arc
							(start -0.3048 -0.2032)
							(mid -0.275042 -0.275042)
							(end -0.2032 -0.3048)
						)
						(arc
							(start 0.2032 -0.3048)
							(mid 0.275042 -0.275042)
							(end 0.3048 -0.2032)
						)
					)
					(width 0)
					(fill yes)
				)
			)
		)
		(pad "2" smd custom
			(at 0 0.4445 270)
			(size 0.1524 0.1524)
			(layers "B.Cu" "B.Mask" "B.Paste")
			(net "GND")
			(options
				(clearance outline)
				(anchor circle)
			)
			(primitives
				(gr_poly
					(pts
						(arc
							(start 0.3048 0.2032)
							(mid 0.275042 0.275042)
							(end 0.2032 0.3048)
						)
						(arc
							(start -0.2032 0.3048)
							(mid -0.275042 0.275042)
							(end -0.3048 0.2032)
						)
						(arc
							(start -0.3048 -0.2032)
							(mid -0.275042 -0.275042)
							(end -0.2032 -0.3048)
						)
						(arc
							(start 0.2032 -0.3048)
							(mid 0.275042 -0.275042)
							(end 0.3048 -0.2032)
						)
					)
					(width 0)
					(fill yes)
				)
			)
		)
	)
	(footprint ""
		(layer "B.Cu")
		(at 188.9252 -70.7644)
		(property "Reference" "TP92"
			(at 0 0 0)
			(layer "B.SilkS")
			(hide yes)
			(effects
				(font
					(size 1.27 1.27)
				)
				(justify mirror)
			)
		)
		(property "Value" "TPAD28-2-GP"
			(at 0.0127 -1.6637 0)
			(unlocked yes)
			(layer "B.Fab")
			(hide yes)
			(effects
				(font
					(size 1.016 1.016)
					(thickness 0.1524)
				)
				(justify mirror)
			)
		)
		(property "Device Type" "TPAD28"
			(at 0.0127 -3.1877 0)
			(unlocked yes)
			(layer "B.Fab")
			(hide yes)
			(effects
				(font
					(size 1.016 1.016)
					(thickness 0.1524)
				)
				(justify mirror)
			)
		)
		(duplicate_pad_numbers_are_jumpers no)
		(fp_poly
			(pts
				(arc
					(start 0.3556 0)
					(mid -0.3556 0)
					(end 0.3556 0)
				)
			)
			(stroke
				(width 0)
				(type default)
			)
			(fill no)
			(layer "B.CrtYd")
		)
		(fp_poly
			(pts
				(arc
					(start 0.6096 0)
					(mid -0.6096 0)
					(end 0.6096 0)
				)
			)
			(stroke
				(width 0)
				(type default)
			)
			(fill no)
			(layer "B.Fab")
		)
		(pad "1" smd circle
			(at 0 0 180)
			(size 0.7112 0.7112)
			(layers "B.Cu" "B.Mask" "B.Paste")
			(net "IOC_GPIO_7")
		)
	)
)
